(kicad_pcb
	(version 20241229)
	(generator "pcbnew")
	(generator_version "9.0")
	(general
		(thickness 1.62)
		(legacy_teardrops no)
	)
	(paper "A3")
	(title_block
		(title "COM Express 7 Baseboard")
		(date "2025-02-04")
		(rev "1.1.2")
		(company "Antmicro Ltd")
		(comment 1 "www.antmicro.com")
		(comment 9 "footprints 44-48 of 802")
	)
	(layers
		(0 "F.Cu" signal)
		(4 "In1.Cu" signal)
		(6 "In2.Cu" signal)
		(8 "In3.Cu" signal)
		(10 "In4.Cu" signal)
		(12 "In5.Cu" signal)
		(14 "In6.Cu" signal)
		(2 "B.Cu" signal)
		(9 "F.Adhes" user "F.Adhesive")
		(11 "B.Adhes" user "B.Adhesive")
		(13 "F.Paste" user)
		(15 "B.Paste" user)
		(5 "F.SilkS" user "F.Silkscreen")
		(7 "B.SilkS" user "B.Silkscreen")
		(1 "F.Mask" user)
		(3 "B.Mask" user)
		(17 "Dwgs.User" user "User.Drawings")
		(19 "Cmts.User" user "User.Comments")
		(21 "Eco1.User" user "User.Eco1")
		(23 "Eco2.User" user "User.Eco2")
		(25 "Edge.Cuts" user)
		(27 "Margin" user)
		(31 "F.CrtYd" user "F.Courtyard")
		(29 "B.CrtYd" user "B.Courtyard")
		(35 "F.Fab" user)
		(33 "B.Fab" user)
	)
	(footprint "antmicro-footprints:R_0402_1005Metric"
		(layer "F.Cu")
		(at 261.35 94.337)
		(descr "Resistor SMD 0402")
		(tags "resistor SMD 0402")
		(property "Reference" "R144"
			(at -1.45 1.423 0)
			(layer "F.SilkS")
			(effects
				(font
					(size 0.7 0.7)
					(thickness 0.15)
				)
				(justify left bottom)
			)
		)
		(property "Value" "R_100k_0402"
			(at -1.011843 1.772047 0)
			(layer "F.Fab")
			(effects
				(font
					(size 0.7 0.7)
					(thickness 0.15)
				)
				(justify left bottom)
			)
		)
		(property "Datasheet" "https://www.bourns.com/docs/product-datasheets/cr.pdf"
			(at 0 0 0)
			(layer "F.Fab")
			(hide yes)
			(effects
				(font
					(size 1.27 1.27)
					(thickness 0.15)
				)
			)
		)
		(property "Author" "Antmicro"
			(at 0 0 0)
			(layer "F.Fab")
			(hide yes)
			(effects
				(font
					(size 1 1)
					(thickness 0.15)
				)
			)
		)
		(property "License" "Apache-2.0"
			(at 0 0 0)
			(layer "F.Fab")
			(hide yes)
			(effects
				(font
					(size 1 1)
					(thickness 0.15)
				)
			)
		)
		(property "MPN" "CR0402-FX-1003GLF"
			(at 0 0 0)
			(layer "F.Fab")
			(hide yes)
			(effects
				(font
					(size 1 1)
					(thickness 0.15)
				)
			)
		)
		(property "Manufacturer" "Bourns"
			(at 0 0 0)
			(layer "F.Fab")
			(hide yes)
			(effects
				(font
					(size 1 1)
					(thickness 0.15)
				)
			)
		)
		(property "Public" "False"
			(at 0 0 0)
			(layer "F.Fab")
			(hide yes)
			(effects
				(font
					(size 1 1)
					(thickness 0.15)
				)
			)
		)
		(property "Tolerance" "1%"
			(at 0 0 0)
			(layer "F.Fab")
			(hide yes)
			(effects
				(font
					(size 1 1)
					(thickness 0.15)
				)
			)
		)
		(property "Val" "100k"
			(at 0 0 0)
			(layer "F.Fab")
			(hide yes)
			(effects
				(font
					(size 1 1)
					(thickness 0.15)
				)
			)
		)
		(sheetname "Misc")
		(sheetfile "misc.kicad_sch")
		(attr smd)
		(fp_rect
			(start -0.925 -0.47)
			(end 0.925 0.47)
			(stroke
				(width 0.05)
				(type default)
			)
			(fill no)
			(layer "F.CrtYd")
		)
		(fp_rect
			(start -0.5 -0.25)
			(end 0.5 0.25)
			(stroke
				(width 0.15)
				(type solid)
			)
			(fill no)
			(layer "F.Fab")
		)
		(pad "1" smd roundrect
			(at -0.48 0)
			(size 0.59 0.64)
			(layers "F.Cu" "F.Mask" "F.Paste")
			(roundrect_rratio 0.25)
			(net 538 "Net-(Q5-D)")
			(pintype "passive")
			(teardrops
				(best_length_ratio 0.2)
				(max_length 1)
				(best_width_ratio 0.9)
				(max_width 2)
				(curved_edges yes)
				(filter_ratio 0.9)
				(enabled yes)
				(allow_two_segments yes)
				(prefer_zone_connections yes)
			)
		)
		(pad "2" smd roundrect
			(at 0.48 0)
			(size 0.59 0.64)
			(layers "F.Cu" "F.Mask" "F.Paste")
			(roundrect_rratio 0.25)
			(net 2 "+3V3")
			(pintype "passive")
			(teardrops
				(best_length_ratio 0.2)
				(max_length 1)
				(best_width_ratio 0.9)
				(max_width 2)
				(curved_edges yes)
				(filter_ratio 0.9)
				(enabled yes)
				(allow_two_segments yes)
				(prefer_zone_connections yes)
			)
		)
	)
	(footprint "antmicro-footprints:R_0201"
		(layer "F.Cu")
		(at 135.17 147.31 90)
		(descr "Resistor SMD 0201")
		(tags "resistor SMD 0201")
		(property "Reference" "R290"
			(at -4.099 0.58 90)
			(layer "F.SilkS")
			(effects
				(font
					(size 0.7 0.7)
					(thickness 0.15)
				)
				(justify left bottom)
			)
		)
		(property "Value" "R_0R_0201"
			(at 0 1.25 90)
			(layer "F.Fab")
			(effects
				(font
					(size 0.7 0.7)
					(thickness 0.15)
				)
				(justify left bottom)
			)
		)
		(property "Datasheet" "https://www.bourns.com/docs/product-datasheets/cr.pdf"
			(at 0 0 90)
			(layer "F.Fab")
			(hide yes)
			(effects
				(font
					(size 1.27 1.27)
					(thickness 0.15)
				)
			)
		)
		(property "Author" "Antmicro"
			(at 282.48 12.14 0)
			(layer "F.Fab")
			(hide yes)
			(effects
				(font
					(size 1 1)
					(thickness 0.15)
				)
			)
		)
		(property "License" "Apache-2.0"
			(at 282.48 12.14 0)
			(layer "F.Fab")
			(hide yes)
			(effects
				(font
					(size 1 1)
					(thickness 0.15)
				)
			)
		)
		(property "MPN" "CR0201-FX-0R00GLF"
			(at 282.48 12.14 0)
			(layer "F.Fab")
			(hide yes)
			(effects
				(font
					(size 1 1)
					(thickness 0.15)
				)
			)
		)
		(property "Manufacturer" "Bourns"
			(at 282.48 12.14 0)
			(layer "F.Fab")
			(hide yes)
			(effects
				(font
					(size 1 1)
					(thickness 0.15)
				)
			)
		)
		(property "Tolerance" "1%"
			(at 282.48 12.14 0)
			(layer "F.Fab")
			(hide yes)
			(effects
				(font
					(size 1 1)
					(thickness 0.15)
				)
			)
		)
		(property "Val" "0R"
			(at 282.48 12.14 0)
			(layer "F.Fab")
			(hide yes)
			(effects
				(font
					(size 1 1)
					(thickness 0.15)
				)
			)
		)
		(sheetname "KR to SFI #2")
		(sheetfile "kr_sfi.kicad_sch")
		(attr smd)
		(fp_rect
			(start -0.7 -0.35)
			(end 0.7 0.35)
			(stroke
				(width 0.05)
				(type default)
			)
			(fill no)
			(layer "F.CrtYd")
		)
		(fp_rect
			(start -0.3 -0.15)
			(end 0.298 0.148)
			(stroke
				(width 0.15)
				(type solid)
			)
			(fill no)
			(layer "F.Fab")
		)
		(pad "" smd roundrect
			(at -0.346 0 90)
			(size 0.318 0.36)
			(layers "F.Paste")
			(roundrect_rratio 0.25)
			(teardrops
				(best_length_ratio 0.2)
				(max_length 1)
				(best_width_ratio 0.9)
				(max_width 2)
				(curved_edges yes)
				(filter_ratio 0.9)
				(enabled yes)
				(allow_two_segments yes)
				(prefer_zone_connections yes)
			)
		)
		(pad "" smd roundrect
			(at 0.344 0 90)
			(size 0.318 0.36)
			(layers "F.Paste")
			(roundrect_rratio 0.25)
			(teardrops
				(best_length_ratio 0.2)
				(max_length 1)
				(best_width_ratio 0.9)
				(max_width 2)
				(curved_edges yes)
				(filter_ratio 0.9)
				(enabled yes)
				(allow_two_segments yes)
				(prefer_zone_connections yes)
			)
		)
		(pad "1" smd roundrect
			(at -0.32 0 90)
			(size 0.46 0.4)
			(layers "F.Cu" "F.Mask")
			(roundrect_rratio 0.25)
			(net 427 "/2xSFP+/10GKR_SFP1.RX+")
			(pintype "passive")
			(teardrops
				(best_length_ratio 0.2)
				(max_length 1)
				(best_width_ratio 0.9)
				(max_width 2)
				(curved_edges yes)
				(filter_ratio 0.9)
				(enabled yes)
				(allow_two_segments yes)
				(prefer_zone_connections yes)
			)
		)
		(pad "2" smd roundrect
			(at 0.32 0 90)
			(size 0.46 0.4)
			(layers "F.Cu" "F.Mask")
			(roundrect_rratio 0.25)
			(net 687 "/2xSFP+/KR to SFI #2/KR_R.RX+")
			(pintype "passive")
			(teardrops
				(best_length_ratio 0.2)
				(max_length 1)
				(best_width_ratio 0.9)
				(max_width 2)
				(curved_edges yes)
				(filter_ratio 0.9)
				(enabled yes)
				(allow_two_segments yes)
				(prefer_zone_connections yes)
			)
		)
	)
	(footprint "antmicro-footprints:TP_SMD_0.75mm"
		(layer "F.Cu")
		(at 151.15 129.56)
		(property "Reference" "TP63"
			(at 0.45 -1.25 90)
			(layer "F.SilkS")
			(effects
				(font
					(size 0.7 0.7)
					(thickness 0.15)
				)
				(justify left bottom)
			)
		)
		(property "Value" "TP_0.75mm_SMD"
			(at 0 1.2 0)
			(layer "F.Fab")
			(effects
				(font
					(size 0.7 0.7)
					(thickness 0.15)
				)
				(justify left bottom)
			)
		)
		(property "Author" "Antmicro"
			(at 0 0 0)
			(layer "F.Fab")
			(hide yes)
			(effects
				(font
					(size 1 1)
					(thickness 0.15)
				)
			)
		)
		(property "License" "Apache-2.0"
			(at 0 0 0)
			(layer "F.Fab")
			(hide yes)
			(effects
				(font
					(size 1 1)
					(thickness 0.15)
				)
			)
		)
		(property "MPN" ""
			(at 0 0 0)
			(layer "F.Fab")
			(hide yes)
			(effects
				(font
					(size 1 1)
					(thickness 0.15)
				)
			)
		)
		(property "Manufacturer" ""
			(at 0 0 0)
			(layer "F.Fab")
			(hide yes)
			(effects
				(font
					(size 1 1)
					(thickness 0.15)
				)
			)
		)
		(property "Public" "False"
			(at 0 0 0)
			(layer "F.Fab")
			(hide yes)
			(effects
				(font
					(size 1 1)
					(thickness 0.15)
				)
			)
		)
		(sheetname "KR to SFI #1")
		(sheetfile "kr_sfi.kicad_sch")
		(attr exclude_from_pos_files exclude_from_bom)
		(fp_circle
			(center 0 0)
			(end 0.475 0)
			(stroke
				(width 0.05)
				(type default)
			)
			(fill no)
			(layer "F.CrtYd")
		)
		(pad "1" smd circle
			(at 0 0)
			(size 0.75 0.75)
			(layers "F.Cu" "F.Mask")
			(net 726 "/2xSFP+/KR to SFI #1/~{TRST}")
			(pinfunction "1")
			(pintype "passive")
			(teardrops
				(best_length_ratio 0.4)
				(max_length 1)
				(best_width_ratio 0.9)
				(max_width 2)
				(curved_edges yes)
				(filter_ratio 0.9)
				(enabled yes)
				(allow_two_segments yes)
				(prefer_zone_connections yes)
			)
		)
	)
	(footprint "antmicro-footprints:Conn_Molex_KK_1x4_0470531000"
		(layer "F.Cu")
		(at 266.240708 71.86 180)
		(property "Reference" "J9"
			(at 7.92 -3.85 0)
			(layer "F.SilkS")
			(effects
				(font
					(size 0.7 0.7)
					(thickness 0.15)
				)
				(justify right bottom)
			)
		)
		(property "Value" "Molex_KK_1x4_0470531000"
			(at 0 4.7 0)
			(layer "F.Fab")
			(effects
				(font
					(size 0.7 0.7)
					(thickness 0.15)
				)
				(justify right bottom)
			)
		)
		(property "Datasheet" "https://tools.molex.com/pdm_docs/sd/470531000_sd.pdf"
			(at 0 0 180)
			(layer "F.Fab")
			(hide yes)
			(effects
				(font
					(size 1.27 1.27)
					(thickness 0.15)
				)
			)
		)
		(property "Author" "Antmicro"
			(at 532.481416 143.72 0)
			(layer "F.Fab")
			(hide yes)
			(effects
				(font
					(size 1 1)
					(thickness 0.15)
				)
			)
		)
		(property "License" "Apache-2.0"
			(at 532.481416 143.72 0)
			(layer "F.Fab")
			(hide yes)
			(effects
				(font
					(size 1 1)
					(thickness 0.15)
				)
			)
		)
		(property "MPN" "0470531000"
			(at 532.481416 143.72 0)
			(layer "F.Fab")
			(hide yes)
			(effects
				(font
					(size 1 1)
					(thickness 0.15)
				)
			)
		)
		(property "Manufacturer" "Molex"
			(at 532.481416 143.72 0)
			(layer "F.Fab")
			(hide yes)
			(effects
				(font
					(size 1 1)
					(thickness 0.15)
				)
			)
		)
		(sheetname "Misc")
		(sheetfile "misc.kicad_sch")
		(attr through_hole)
		(fp_line
			(start 8.95 3.4)
			(end -1.35 3.4)
			(stroke
				(width 0.15)
				(type solid)
			)
			(layer "F.SilkS")
		)
		(fp_line
			(start 8.95 -2.55)
			(end 8.95 3.4)
			(stroke
				(width 0.15)
				(type solid)
			)
			(layer "F.SilkS")
		)
		(fp_line
			(start 5.75 -2.55)
			(end 8.95 -2.55)
			(stroke
				(width 0.15)
				(type solid)
			)
			(layer "F.SilkS")
		)
		(fp_line
			(start 5.08 2.29)
			(end 5.08 3.3)
			(stroke
				(width 0.15)
				(type solid)
			)
			(layer "F.SilkS")
		)
		(fp_line
			(start 0 3.3)
			(end 0 2.29)
			(stroke
				(width 0.15)
				(type solid)
			)
			(layer "F.SilkS")
		)
		(fp_line
			(start 0 2.29)
			(end 5.08 2.29)
			(stroke
				(width 0.15)
				(type solid)
			)
			(layer "F.SilkS")
		)
		(fp_line
			(start -1.35 3.4)
			(end -1.35 -2.6)
			(stroke
				(width 0.15)
				(type solid)
			)
			(layer "F.SilkS")
		)
		(fp_line
			(start -1.35 -2.6)
			(end 4.4 -2.6)
			(stroke
				(width 0.15)
				(type solid)
			)
			(layer "F.SilkS")
		)
		(fp_circle
			(center 0 -3)
			(end 0.05 -3)
			(stroke
				(width 0.15)
				(type solid)
			)
			(fill yes)
			(layer "F.SilkS")
		)
		(fp_rect
			(start -1.54 -2.96)
			(end 9.16 3.55)
			(stroke
				(width 0.05)
				(type solid)
			)
			(fill no)
			(layer "F.CrtYd")
		)
		(fp_line
			(start 8.85 3.3)
			(end -1.2 3.3)
			(stroke
				(width 0.15)
				(type solid)
			)
			(layer "F.Fab")
		)
		(fp_line
			(start 8.85 -2.5)
			(end 8.85 3.3)
			(stroke
				(width 0.15)
				(type solid)
			)
			(layer "F.Fab")
		)
		(fp_line
			(start 5.75 -2.5)
			(end 8.85 -2.5)
			(stroke
				(width 0.15)
				(type solid)
			)
			(layer "F.Fab")
		)
		(fp_line
			(start 5.1 3.3)
			(end 5.1 2.3)
			(stroke
				(width 0.15)
				(type solid)
			)
			(layer "F.Fab")
		)
		(fp_line
			(start 5.1 2.3)
			(end 0 2.3)
			(stroke
				(width 0.15)
				(type solid)
			)
			(layer "F.Fab")
		)
		(fp_line
			(start 0 2.3)
			(end 0 3.3)
			(stroke
				(width 0.15)
				(type solid)
			)
			(layer "F.Fab")
		)
		(fp_line
			(start -1.2 3.3)
			(end -1.25 3.3)
			(stroke
				(width 0.15)
				(type solid)
			)
			(layer "F.Fab")
		)
		(fp_line
			(start -1.25 3.3)
			(end -1.25 -2.5)
			(stroke
				(width 0.15)
				(type solid)
			)
			(layer "F.Fab")
		)
		(fp_line
			(start -1.25 -2.5)
			(end 4.4 -2.5)
			(stroke
				(width 0.15)
				(type solid)
			)
			(layer "F.Fab")
		)
		(pad "" np_thru_hole circle
			(at 5.08 -2.16 270)
			(size 1.1 1.1)
			(drill 1.1)
			(layers "*.Cu" "*.Mask")
		)
		(pad "1" thru_hole rect
			(at 0 0 270)
			(size 2.03 1.73)
			(drill 1.02)
			(layers "*.Cu" "*.Mask")
			(remove_unused_layers no)
			(net 1 "GND")
			(pintype "passive")
			(teardrops
				(best_length_ratio 0.2)
				(max_length 1)
				(best_width_ratio 0.9)
				(max_width 2)
				(curved_edges yes)
				(filter_ratio 0.9)
				(enabled yes)
				(allow_two_segments yes)
				(prefer_zone_connections yes)
			)
		)
		(pad "2" thru_hole oval
			(at 2.54 0 270)
			(size 2.03 1.73)
			(drill 1.02)
			(layers "*.Cu" "*.Mask")
			(remove_unused_layers no)
			(net 81 "/Misc/FAN_12V")
			(pintype "passive")
			(teardrops
				(best_length_ratio 0.2)
				(max_length 1)
				(best_width_ratio 0.9)
				(max_width 2)
				(curved_edges yes)
				(filter_ratio 0.9)
				(enabled yes)
				(allow_two_segments yes)
				(prefer_zone_connections yes)
			)
		)
		(pad "3" thru_hole oval
			(at 5.08 0 270)
			(size 2.03 1.73)
			(drill 1.02)
			(layers "*.Cu" "*.Mask")
			(remove_unused_layers no)
			(net 279 "/Misc/TACH_{A5V}")
			(pintype "passive")
			(teardrops
				(best_length_ratio 0.2)
				(max_length 1)
				(best_width_ratio 0.9)
				(max_width 2)
				(curved_edges yes)
				(filter_ratio 0.9)
				(enabled yes)
				(allow_two_segments yes)
				(prefer_zone_connections yes)
			)
		)
		(pad "4" thru_hole oval
			(at 7.62 0 270)
			(size 2.03 1.73)
			(drill 1.02)
			(layers "*.Cu" "*.Mask")
			(remove_unused_layers no)
			(net 280 "/Misc/PWM_{A5V}")
			(pintype "passive")
			(teardrops
				(best_length_ratio 0.2)
				(max_length 1)
				(best_width_ratio 0.9)
				(max_width 2)
				(curved_edges yes)
				(filter_ratio 0.9)
				(enabled yes)
				(allow_two_segments yes)
				(prefer_zone_connections yes)
			)
		)
	)
	(footprint "antmicro-footprints:R_0402_1005Metric"
		(layer "F.Cu")
		(at 126.425 84.060001 180)
		(descr "Resistor SMD 0402")
		(tags "resistor SMD 0402")
		(property "Reference" "R239"
			(at -1.575 -6.4 0)
			(layer "F.SilkS")
			(effects
				(font
					(size 0.7 0.7)
					(thickness 0.15)
				)
				(justify right bottom)
			)
		)
		(property "Value" "R_0R_0402"
			(at -1.011843 1.772047 0)
			(layer "F.Fab")
			(effects
				(font
					(size 0.7 0.7)
					(thickness 0.15)
				)
				(justify right bottom)
			)
		)
		(property "Datasheet" "https://industrial.panasonic.com/cdbs/www-data/pdf/RDA0000/AOA0000C301.pdf"
			(at 0 0 180)
			(layer "F.Fab")
			(hide yes)
			(effects
				(font
					(size 1.27 1.27)
					(thickness 0.15)
				)
			)
		)
		(property "Author" "Antmicro"
			(at 252.85 168.120002 0)
			(layer "F.Fab")
			(hide yes)
			(effects
				(font
					(size 1 1)
					(thickness 0.15)
				)
			)
		)
		(property "Current" "1A"
			(at 252.85 168.120002 0)
			(layer "F.Fab")
			(hide yes)
			(effects
				(font
					(size 1 1)
					(thickness 0.15)
				)
			)
		)
		(property "License" "Apache-2.0"
			(at 252.85 168.120002 0)
			(layer "F.Fab")
			(hide yes)
			(effects
				(font
					(size 1 1)
					(thickness 0.15)
				)
			)
		)
		(property "MPN" "ERJ2GE0R00X"
			(at 252.85 168.120002 0)
			(layer "F.Fab")
			(hide yes)
			(effects
				(font
					(size 1 1)
					(thickness 0.15)
				)
			)
		)
		(property "Manufacturer" "Panasonic"
			(at 252.85 168.120002 0)
			(layer "F.Fab")
			(hide yes)
			(effects
				(font
					(size 1 1)
					(thickness 0.15)
				)
			)
		)
		(property "Public" "False"
			(at 252.85 168.120002 0)
			(layer "F.Fab")
			(hide yes)
			(effects
				(font
					(size 1 1)
					(thickness 0.15)
				)
			)
		)
		(property "Tolerance" ""
			(at 252.85 168.120002 0)
			(layer "F.Fab")
			(hide yes)
			(effects
				(font
					(size 1 1)
					(thickness 0.15)
				)
			)
		)
		(property "Val" "0R"
			(at 252.85 168.120002 0)
			(layer "F.Fab")
			(hide yes)
			(effects
				(font
					(size 1 1)
					(thickness 0.15)
				)
			)
		)
		(sheetname "GPIO expander")
		(sheetfile "gpio_exp.kicad_sch")
		(attr smd)
		(fp_rect
			(start -0.925 -0.47)
			(end 0.925 0.47)
			(stroke
				(width 0.05)
				(type default)
			)
			(fill no)
			(layer "F.CrtYd")
		)
		(fp_rect
			(start -0.5 -0.25)
			(end 0.5 0.25)
			(stroke
				(width 0.15)
				(type solid)
			)
			(fill no)
			(layer "F.Fab")
		)
		(pad "1" smd roundrect
			(at -0.48 0 180)
			(size 0.59 0.64)
			(layers "F.Cu" "F.Mask" "F.Paste")
			(roundrect_rratio 0.25)
			(net 640 "Net-(U41-IO0_1)")
			(pintype "passive")
			(teardrops
				(best_length_ratio 0.2)
				(max_length 1)
				(best_width_ratio 0.9)
				(max_width 2)
				(curved_edges yes)
				(filter_ratio 0.9)
				(enabled yes)
				(allow_two_segments yes)
				(prefer_zone_connections yes)
			)
		)
		(pad "2" smd roundrect
			(at 0.48 0 180)
			(size 0.59 0.64)
			(layers "F.Cu" "F.Mask" "F.Paste")
			(roundrect_rratio 0.25)
			(net 943 "/GPIO expander/GPIOEX1")
			(pintype "passive")
			(teardrops
				(best_length_ratio 0.2)
				(max_length 1)
				(best_width_ratio 0.9)
				(max_width 2)
				(curved_edges yes)
				(filter_ratio 0.9)
				(enabled yes)
				(allow_two_segments yes)
				(prefer_zone_connections yes)
			)
		)
	)
)
